(kicad_pcb
	(version 20260206)
	(generator "pcbnew")
	(generator_version "10.0")
	(general
		(thickness 1.6)
		(legacy_teardrops no)
	)
	(paper "A4")
	(title_block
		(title "04192023_DAF0TMB3IC0_F0TG_MB_C_brd_V02_OCP.brd")
		(comment 1 "Grand Teton / footprints 7201-7208 of 8354")
	)
	(layers
		(0 "F.Cu" signal "TOP")
		(4 "In1.Cu" signal "GND")
		(6 "In2.Cu" signal "IN1")
		(8 "In3.Cu" signal "GND1")
		(10 "In4.Cu" signal "IN2")
		(12 "In5.Cu" signal "GND2")
		(14 "In6.Cu" signal "IN3")
		(16 "In7.Cu" signal "GND3")
		(18 "In8.Cu" signal "VCC")
		(20 "In9.Cu" signal "VCC1")
		(22 "In10.Cu" signal "GND4")
		(24 "In11.Cu" signal "IN4")
		(26 "In12.Cu" signal "GND5")
		(28 "In13.Cu" signal "IN5")
		(30 "In14.Cu" signal "GND6")
		(32 "In15.Cu" signal "IN6")
		(34 "In16.Cu" signal "GND7")
		(2 "B.Cu" signal "BOTTOM")
		(9 "F.Adhes" user "F.Adhesive")
		(11 "B.Adhes" user "B.Adhesive")
		(13 "F.Paste" user "Package Geometry/Pastemask Top")
		(15 "B.Paste" user "Package Geometry/Pastemask Bottom")
		(5 "F.SilkS" user "Ref Des/Silkscreen Top")
		(7 "B.SilkS" user "Ref Des/Silkscreen Bottom")
		(1 "F.Mask" user "Board Geometry/Soldermask Top")
		(3 "B.Mask" user "Board Geometry/Soldermask Bottom")
		(17 "Dwgs.User" user "User.Drawings")
		(19 "Cmts.User" user "User.Comments")
		(21 "Eco1.User" user "User.Eco1")
		(23 "Eco2.User" user "User.Eco2")
		(25 "Edge.Cuts" user "Board Geometry/Outline")
		(27 "Margin" user)
		(31 "F.CrtYd" user "Package Geometry/Place Bound Top")
		(29 "B.CrtYd" user "Package Geometry/Place Bound Bottom")
		(35 "F.Fab" user "Ref Des/Assembly Top")
		(33 "B.Fab" user "Ref Des/Assembly Bottom")
	)
	(footprint ""
		(layer "B.Cu")
		(at 32.639 -364.871)
		(property "Reference" "PR244"
			(at 0 0 0)
			(layer "B.SilkS")
			(hide yes)
			(effects
				(font
					(size 1.27 1.27)
				)
				(justify mirror)
			)
		)
		(property "Value" ""
			(at 0 0 0)
			(layer "B.Fab")
			(effects
				(font
					(size 1.27 1.27)
				)
				(justify mirror)
			)
		)
		(duplicate_pad_numbers_are_jumpers no)
		(fp_line
			(start -0.7874 -0.4064)
			(end -0.7874 0.4064)
			(stroke
				(width 0.1524)
				(type default)
			)
			(layer "B.SilkS")
		)
		(fp_line
			(start -0.7874 0.4064)
			(end 0.7874 0.4064)
			(stroke
				(width 0.1524)
				(type default)
			)
			(layer "B.SilkS")
		)
		(fp_line
			(start 0.7874 -0.4064)
			(end -0.7874 -0.4064)
			(stroke
				(width 0.1524)
				(type default)
			)
			(layer "B.SilkS")
		)
		(fp_line
			(start 0.7874 0.4064)
			(end 0.7874 -0.4064)
			(stroke
				(width 0.1524)
				(type default)
			)
			(layer "B.SilkS")
		)
		(fp_line
			(start -0.67945 -0.3048)
			(end -0.67945 0.3048)
			(stroke
				(width 0.1)
				(type default)
			)
			(layer "B.Fab")
		)
		(fp_line
			(start -0.67945 0.3048)
			(end -0.120396 0.3048)
			(stroke
				(width 0.1)
				(type default)
			)
			(layer "B.Fab")
		)
		(fp_line
			(start -0.12065 -0.3048)
			(end -0.67945 -0.3048)
			(stroke
				(width 0.1)
				(type default)
			)
			(layer "B.Fab")
		)
		(fp_line
			(start -0.12065 -0.2794)
			(end -0.12065 -0.3048)
			(stroke
				(width 0.1)
				(type default)
			)
			(layer "B.Fab")
		)
		(fp_line
			(start -0.120396 0.2794)
			(end 0.12065 0.2794)
			(stroke
				(width 0.1)
				(type default)
			)
			(layer "B.Fab")
		)
		(fp_line
			(start -0.120396 0.3048)
			(end -0.120396 0.2794)
			(stroke
				(width 0.1)
				(type default)
			)
			(layer "B.Fab")
		)
		(fp_line
			(start 0.12065 -0.305054)
			(end 0.12065 -0.2794)
			(stroke
				(width 0.1)
				(type default)
			)
			(layer "B.Fab")
		)
		(fp_line
			(start 0.12065 -0.2794)
			(end -0.12065 -0.2794)
			(stroke
				(width 0.1)
				(type default)
			)
			(layer "B.Fab")
		)
		(fp_line
			(start 0.12065 0.2794)
			(end 0.12065 0.3048)
			(stroke
				(width 0.1)
				(type default)
			)
			(layer "B.Fab")
		)
		(fp_line
			(start 0.12065 0.3048)
			(end 0.67945 0.3048)
			(stroke
				(width 0.1)
				(type default)
			)
			(layer "B.Fab")
		)
		(fp_line
			(start 0.67945 -0.305054)
			(end 0.12065 -0.305054)
			(stroke
				(width 0.1)
				(type default)
			)
			(layer "B.Fab")
		)
		(fp_line
			(start 0.67945 0.3048)
			(end 0.67945 -0.305054)
			(stroke
				(width 0.1)
				(type default)
			)
			(layer "B.Fab")
		)
		(pad "1" smd circle
			(at 0.40005 0 180)
			(size 0 0)
			(layers "B.Cu" "B.Mask" "B.Paste")
			(net "PVDDCR_CPU1_P1_EN1_ADDR_CFG")
		)
		(pad "2" smd circle
			(at -0.40005 0 180)
			(size 0 0)
			(layers "B.Cu" "B.Mask" "B.Paste")
			(net "GND")
		)
	)
	(footprint ""
		(layer "B.Cu")
		(at 333.561436 -151.069294 90)
		(property "Reference" "PC285"
			(at 0 0 90)
			(layer "B.SilkS")
			(hide yes)
			(effects
				(font
					(size 1.27 1.27)
				)
				(justify mirror)
			)
		)
		(property "Value" ""
			(at 0 0 90)
			(layer "B.Fab")
			(effects
				(font
					(size 1.27 1.27)
				)
				(justify mirror)
			)
		)
		(duplicate_pad_numbers_are_jumpers no)
		(fp_line
			(start 1.524 -0.762)
			(end -1.524 -0.762)
			(stroke
				(width 0.1524)
				(type default)
			)
			(layer "B.SilkS")
		)
		(fp_line
			(start -1.524 -0.762)
			(end -1.524 0.762)
			(stroke
				(width 0.1524)
				(type default)
			)
			(layer "B.SilkS")
		)
		(fp_line
			(start 1.524 0.762)
			(end 1.524 -0.762)
			(stroke
				(width 0.1524)
				(type default)
			)
			(layer "B.SilkS")
		)
		(fp_line
			(start -1.524 0.762)
			(end 1.524 0.762)
			(stroke
				(width 0.1524)
				(type default)
			)
			(layer "B.SilkS")
		)
		(fp_line
			(start 1.1049 -0.724916)
			(end 1.1049 0.724916)
			(stroke
				(width 0.1)
				(type default)
			)
			(layer "B.Fab")
		)
		(fp_line
			(start -1.1049 -0.724916)
			(end 1.1049 -0.724916)
			(stroke
				(width 0.1)
				(type default)
			)
			(layer "B.Fab")
		)
		(fp_line
			(start 1.1049 0.724916)
			(end -1.1049 0.724916)
			(stroke
				(width 0.1)
				(type default)
			)
			(layer "B.Fab")
		)
		(fp_line
			(start -1.1049 0.724916)
			(end -1.1049 -0.724916)
			(stroke
				(width 0.1)
				(type default)
			)
			(layer "B.Fab")
		)
		(pad "1" smd rect
			(at 0.889 0 90)
			(size 1.016 1.27)
			(layers "B.Cu" "B.Mask" "B.Paste")
			(net "PVDD18_S5_P0")
		)
		(pad "2" smd rect
			(at -0.889 0 90)
			(size 1.016 1.27)
			(layers "B.Cu" "B.Mask" "B.Paste")
			(net "GND")
		)
	)
	(footprint ""
		(layer "B.Cu")
		(at 421.974518 -175.029622)
		(property "Reference" "TP1"
			(at -0.72136 -1.224788 0)
			(unlocked yes)
			(layer "B.SilkS")
			(effects
				(font
					(size 0.7874 0.5842)
					(thickness 0.1524)
				)
				(justify left mirror)
			)
		)
		(property "Value" ""
			(at 0 0 0)
			(layer "B.Fab")
			(effects
				(font
					(size 1.27 1.27)
				)
				(justify mirror)
			)
		)
		(duplicate_pad_numbers_are_jumpers no)
		(pad "1" smd circle
			(at 0 0 180)
			(size 0.6604 0.6604)
			(layers "B.Cu" "B.Mask" "B.Paste")
			(net "VSENSE_VSS_SENSE_A_P0")
		)
	)
	(footprint ""
		(layer "B.Cu")
		(at 346.518992 -258.830064 180)
		(property "Reference" "C2654"
			(at 0 0 0)
			(layer "B.SilkS")
			(hide yes)
			(effects
				(font
					(size 1.27 1.27)
				)
				(justify mirror)
			)
		)
		(property "Value" ""
			(at 0 0 0)
			(layer "B.Fab")
			(effects
				(font
					(size 1.27 1.27)
				)
				(justify mirror)
			)
		)
		(duplicate_pad_numbers_are_jumpers no)
		(fp_line
			(start 0.7874 0.4064)
			(end 0.7874 -0.4064)
			(stroke
				(width 0.1524)
				(type default)
			)
			(layer "B.SilkS")
		)
		(fp_line
			(start 0.7874 -0.4064)
			(end -0.7874 -0.4064)
			(stroke
				(width 0.1524)
				(type default)
			)
			(layer "B.SilkS")
		)
		(fp_line
			(start -0.7874 0.4064)
			(end 0.7874 0.4064)
			(stroke
				(width 0.1524)
				(type default)
			)
			(layer "B.SilkS")
		)
		(fp_line
			(start -0.7874 -0.4064)
			(end -0.7874 0.4064)
			(stroke
				(width 0.1524)
				(type default)
			)
			(layer "B.SilkS")
		)
		(fp_line
			(start 0.67945 0.3048)
			(end 0.67945 -0.305054)
			(stroke
				(width 0.1)
				(type default)
			)
			(layer "B.Fab")
		)
		(fp_line
			(start 0.67945 -0.305054)
			(end 0.12065 -0.305054)
			(stroke
				(width 0.1)
				(type default)
			)
			(layer "B.Fab")
		)
		(fp_line
			(start 0.12065 0.3048)
			(end 0.67945 0.3048)
			(stroke
				(width 0.1)
				(type default)
			)
			(layer "B.Fab")
		)
		(fp_line
			(start 0.12065 0.2794)
			(end 0.12065 0.3048)
			(stroke
				(width 0.1)
				(type default)
			)
			(layer "B.Fab")
		)
		(fp_line
			(start 0.12065 -0.2794)
			(end -0.12065 -0.2794)
			(stroke
				(width 0.1)
				(type default)
			)
			(layer "B.Fab")
		)
		(fp_line
			(start 0.12065 -0.305054)
			(end 0.12065 -0.2794)
			(stroke
				(width 0.1)
				(type default)
			)
			(layer "B.Fab")
		)
		(fp_line
			(start -0.120396 0.3048)
			(end -0.120396 0.2794)
			(stroke
				(width 0.1)
				(type default)
			)
			(layer "B.Fab")
		)
		(fp_line
			(start -0.120396 0.2794)
			(end 0.12065 0.2794)
			(stroke
				(width 0.1)
				(type default)
			)
			(layer "B.Fab")
		)
		(fp_line
			(start -0.12065 -0.2794)
			(end -0.12065 -0.3048)
			(stroke
				(width 0.1)
				(type default)
			)
			(layer "B.Fab")
		)
		(fp_line
			(start -0.12065 -0.3048)
			(end -0.67945 -0.3048)
			(stroke
				(width 0.1)
				(type default)
			)
			(layer "B.Fab")
		)
		(fp_line
			(start -0.67945 0.3048)
			(end -0.120396 0.3048)
			(stroke
				(width 0.1)
				(type default)
			)
			(layer "B.Fab")
		)
		(fp_line
			(start -0.67945 -0.3048)
			(end -0.67945 0.3048)
			(stroke
				(width 0.1)
				(type default)
			)
			(layer "B.Fab")
		)
		(pad "1" smd circle
			(at 0.40005 0)
			(size 0 0)
			(layers "B.Cu" "B.Mask" "B.Paste")
			(net "PVDDIO_P0")
		)
		(pad "2" smd circle
			(at -0.40005 0)
			(size 0 0)
			(layers "B.Cu" "B.Mask" "B.Paste")
			(net "GND")
		)
	)
	(footprint ""
		(layer "B.Cu")
		(at 125.262386 -267.49883)
		(property "Reference" "C2399"
			(at 0 0 0)
			(layer "B.SilkS")
			(hide yes)
			(effects
				(font
					(size 1.27 1.27)
				)
				(justify mirror)
			)
		)
		(property "Value" ""
			(at 0 0 0)
			(layer "B.Fab")
			(effects
				(font
					(size 1.27 1.27)
				)
				(justify mirror)
			)
		)
		(duplicate_pad_numbers_are_jumpers no)
		(fp_line
			(start -0.7874 -0.4064)
			(end -0.7874 0.4064)
			(stroke
				(width 0.1524)
				(type default)
			)
			(layer "B.SilkS")
		)
		(fp_line
			(start -0.7874 0.4064)
			(end 0.7874 0.4064)
			(stroke
				(width 0.1524)
				(type default)
			)
			(layer "B.SilkS")
		)
		(fp_line
			(start 0.7874 -0.4064)
			(end -0.7874 -0.4064)
			(stroke
				(width 0.1524)
				(type default)
			)
			(layer "B.SilkS")
		)
		(fp_line
			(start 0.7874 0.4064)
			(end 0.7874 -0.4064)
			(stroke
				(width 0.1524)
				(type default)
			)
			(layer "B.SilkS")
		)
		(fp_line
			(start -0.67945 -0.3048)
			(end -0.67945 0.3048)
			(stroke
				(width 0.1)
				(type default)
			)
			(layer "B.Fab")
		)
		(fp_line
			(start -0.67945 0.3048)
			(end -0.120396 0.3048)
			(stroke
				(width 0.1)
				(type default)
			)
			(layer "B.Fab")
		)
		(fp_line
			(start -0.12065 -0.3048)
			(end -0.67945 -0.3048)
			(stroke
				(width 0.1)
				(type default)
			)
			(layer "B.Fab")
		)
		(fp_line
			(start -0.12065 -0.2794)
			(end -0.12065 -0.3048)
			(stroke
				(width 0.1)
				(type default)
			)
			(layer "B.Fab")
		)
		(fp_line
			(start -0.120396 0.2794)
			(end 0.12065 0.2794)
			(stroke
				(width 0.1)
				(type default)
			)
			(layer "B.Fab")
		)
		(fp_line
			(start -0.120396 0.3048)
			(end -0.120396 0.2794)
			(stroke
				(width 0.1)
				(type default)
			)
			(layer "B.Fab")
		)
		(fp_line
			(start 0.12065 -0.305054)
			(end 0.12065 -0.2794)
			(stroke
				(width 0.1)
				(type default)
			)
			(layer "B.Fab")
		)
		(fp_line
			(start 0.12065 -0.2794)
			(end -0.12065 -0.2794)
			(stroke
				(width 0.1)
				(type default)
			)
			(layer "B.Fab")
		)
		(fp_line
			(start 0.12065 0.2794)
			(end 0.12065 0.3048)
			(stroke
				(width 0.1)
				(type default)
			)
			(layer "B.Fab")
		)
		(fp_line
			(start 0.12065 0.3048)
			(end 0.67945 0.3048)
			(stroke
				(width 0.1)
				(type default)
			)
			(layer "B.Fab")
		)
		(fp_line
			(start 0.67945 -0.305054)
			(end 0.12065 -0.305054)
			(stroke
				(width 0.1)
				(type default)
			)
			(layer "B.Fab")
		)
		(fp_line
			(start 0.67945 0.3048)
			(end 0.67945 -0.305054)
			(stroke
				(width 0.1)
				(type default)
			)
			(layer "B.Fab")
		)
		(pad "1" smd circle
			(at 0.40005 0 180)
			(size 0 0)
			(layers "B.Cu" "B.Mask" "B.Paste")
			(net "PVDDCR_CPU1_P1")
		)
		(pad "2" smd circle
			(at -0.40005 0 180)
			(size 0 0)
			(layers "B.Cu" "B.Mask" "B.Paste")
			(net "GND")
		)
	)
	(footprint ""
		(layer "B.Cu")
		(at 255.905 -332.867 180)
		(property "Reference" "R845"
			(at 0 0 0)
			(layer "B.SilkS")
			(hide yes)
			(effects
				(font
					(size 1.27 1.27)
				)
				(justify mirror)
			)
		)
		(property "Value" ""
			(at 0 0 0)
			(layer "B.Fab")
			(effects
				(font
					(size 1.27 1.27)
				)
				(justify mirror)
			)
		)
		(duplicate_pad_numbers_are_jumpers no)
		(fp_line
			(start 0.32512 0.175006)
			(end 0.32512 -0.175006)
			(stroke
				(width 0.1)
				(type default)
			)
			(layer "B.Fab")
		)
		(fp_line
			(start 0.32512 -0.175006)
			(end -0.32512 -0.175006)
			(stroke
				(width 0.1)
				(type default)
			)
			(layer "B.Fab")
		)
		(fp_line
			(start -0.32512 0.175006)
			(end 0.32512 0.175006)
			(stroke
				(width 0.1)
				(type default)
			)
			(layer "B.Fab")
		)
		(fp_line
			(start -0.32512 -0.175006)
			(end -0.32512 0.175006)
			(stroke
				(width 0.1)
				(type default)
			)
			(layer "B.Fab")
		)
		(pad "1" smd rect
			(at 0.2667 0)
			(size 0.3048 0.381)
			(layers "B.Cu" "B.Mask" "B.Paste")
			(net "RT_ROM_SMB_MUX_ADDR2")
		)
		(pad "2" smd rect
			(at -0.2667 0 180)
			(size 0.3048 0.381)
			(layers "B.Cu" "B.Mask" "B.Paste")
			(net "GND")
		)
	)
	(footprint ""
		(layer "B.Cu")
		(at 12.003532 -99.925632 180)
		(property "Reference" "C2033"
			(at 0 0 0)
			(layer "B.SilkS")
			(hide yes)
			(effects
				(font
					(size 1.27 1.27)
				)
				(justify mirror)
			)
		)
		(property "Value" ""
			(at 0 0 0)
			(layer "B.Fab")
			(effects
				(font
					(size 1.27 1.27)
				)
				(justify mirror)
			)
		)
		(duplicate_pad_numbers_are_jumpers no)
		(fp_line
			(start 0.7874 0.4064)
			(end 0.7874 -0.4064)
			(stroke
				(width 0.1524)
				(type default)
			)
			(layer "B.SilkS")
		)
		(fp_line
			(start 0.7874 -0.4064)
			(end -0.7874 -0.4064)
			(stroke
				(width 0.1524)
				(type default)
			)
			(layer "B.SilkS")
		)
		(fp_line
			(start -0.7874 0.4064)
			(end 0.7874 0.4064)
			(stroke
				(width 0.1524)
				(type default)
			)
			(layer "B.SilkS")
		)
		(fp_line
			(start -0.7874 -0.4064)
			(end -0.7874 0.4064)
			(stroke
				(width 0.1524)
				(type default)
			)
			(layer "B.SilkS")
		)
		(fp_line
			(start 0.67945 0.3048)
			(end 0.67945 -0.305054)
			(stroke
				(width 0.1)
				(type default)
			)
			(layer "B.Fab")
		)
		(fp_line
			(start 0.67945 -0.305054)
			(end 0.12065 -0.305054)
			(stroke
				(width 0.1)
				(type default)
			)
			(layer "B.Fab")
		)
		(fp_line
			(start 0.12065 0.3048)
			(end 0.67945 0.3048)
			(stroke
				(width 0.1)
				(type default)
			)
			(layer "B.Fab")
		)
		(fp_line
			(start 0.12065 0.2794)
			(end 0.12065 0.3048)
			(stroke
				(width 0.1)
				(type default)
			)
			(layer "B.Fab")
		)
		(fp_line
			(start 0.12065 -0.2794)
			(end -0.12065 -0.2794)
			(stroke
				(width 0.1)
				(type default)
			)
			(layer "B.Fab")
		)
		(fp_line
			(start 0.12065 -0.305054)
			(end 0.12065 -0.2794)
			(stroke
				(width 0.1)
				(type default)
			)
			(layer "B.Fab")
		)
		(fp_line
			(start -0.120396 0.3048)
			(end -0.120396 0.2794)
			(stroke
				(width 0.1)
				(type default)
			)
			(layer "B.Fab")
		)
		(fp_line
			(start -0.120396 0.2794)
			(end 0.12065 0.2794)
			(stroke
				(width 0.1)
				(type default)
			)
			(layer "B.Fab")
		)
		(fp_line
			(start -0.12065 -0.2794)
			(end -0.12065 -0.3048)
			(stroke
				(width 0.1)
				(type default)
			)
			(layer "B.Fab")
		)
		(fp_line
			(start -0.12065 -0.3048)
			(end -0.67945 -0.3048)
			(stroke
				(width 0.1)
				(type default)
			)
			(layer "B.Fab")
		)
		(fp_line
			(start -0.67945 0.3048)
			(end -0.120396 0.3048)
			(stroke
				(width 0.1)
				(type default)
			)
			(layer "B.Fab")
		)
		(fp_line
			(start -0.67945 -0.3048)
			(end -0.67945 0.3048)
			(stroke
				(width 0.1)
				(type default)
			)
			(layer "B.Fab")
		)
		(pad "1" smd circle
			(at 0.40005 0)
			(size 0 0)
			(layers "B.Cu" "B.Mask" "B.Paste")
			(net "P3V3_AUX_USB_HUB")
		)
		(pad "2" smd circle
			(at -0.40005 0)
			(size 0 0)
			(layers "B.Cu" "B.Mask" "B.Paste")
			(net "GND")
		)
	)
	(footprint ""
		(layer "B.Cu")
		(at 152.202642 -78.76921)
		(property "Reference" "PC865"
			(at 0 0 0)
			(layer "B.SilkS")
			(hide yes)
			(effects
				(font
					(size 1.27 1.27)
				)
				(justify mirror)
			)
		)
		(property "Value" ""
			(at 0 0 0)
			(layer "B.Fab")
			(effects
				(font
					(size 1.27 1.27)
				)
				(justify mirror)
			)
		)
		(duplicate_pad_numbers_are_jumpers no)
		(fp_line
			(start -1.524 -0.762)
			(end -1.524 0.762)
			(stroke
				(width 0.1524)
				(type default)
			)
			(layer "B.SilkS")
		)
		(fp_line
			(start -1.524 0.762)
			(end 1.524 0.762)
			(stroke
				(width 0.1524)
				(type default)
			)
			(layer "B.SilkS")
		)
		(fp_line
			(start 1.524 -0.762)
			(end -1.524 -0.762)
			(stroke
				(width 0.1524)
				(type default)
			)
			(layer "B.SilkS")
		)
		(fp_line
			(start 1.524 0.762)
			(end 1.524 -0.762)
			(stroke
				(width 0.1524)
				(type default)
			)
			(layer "B.SilkS")
		)
		(fp_line
			(start -1.1049 -0.724916)
			(end 1.1049 -0.724916)
			(stroke
				(width 0.1)
				(type default)
			)
			(layer "B.Fab")
		)
		(fp_line
			(start -1.1049 0.724916)
			(end -1.1049 -0.724916)
			(stroke
				(width 0.1)
				(type default)
			)
			(layer "B.Fab")
		)
		(fp_line
			(start 1.1049 -0.724916)
			(end 1.1049 0.724916)
			(stroke
				(width 0.1)
				(type default)
			)
			(layer "B.Fab")
		)
		(fp_line
			(start 1.1049 0.724916)
			(end -1.1049 0.724916)
			(stroke
				(width 0.1)
				(type default)
			)
			(layer "B.Fab")
		)
		(pad "1" smd rect
			(at 0.889 0)
			(size 1.016 1.27)
			(layers "B.Cu" "B.Mask" "B.Paste")
			(net "P1V8_AUX")
		)
		(pad "2" smd rect
			(at -0.889 0)
			(size 1.016 1.27)
			(layers "B.Cu" "B.Mask" "B.Paste")
			(net "GND")
		)
	)
)
